# BASEBOARD_FAB2 (Tioga Pass) — schematic netlist excerpt (pin names and nets, part order shuffled) for the footprints in the layout excerpt that follows; sources: Cadence DE-HDL packaged netlist, KiCad conversion of Wiwynn_Tioga_Pass_MB.brd

R25W109  RES  4.75K 1% CHIP  pkg 0402  page 150 : A = P3V3_STBY ; B = TP_RGMII2TXD3_GPIOU3
C3T13  CAPP  68UF 16V 20% TANT  pkg 3018  page 195 : A = P12V_STBY ; B = GND
R2N4  RES  1.0K 0.1% CHIP  pkg 0402  page 118 : A = P1V05_PCH_STBY_KR_PLL ; B = A_KR0_RBIAS

(kicad_pcb
	(version 20260206)
	(generator "pcbnew")
	(generator_version "10.0")
	(general
		(thickness 1.6)
		(legacy_teardrops no)
	)
	(paper "A4")
	(title_block
		(title "Wiwynn_Tioga_Pass_MB.brd")
		(comment 1 "Tioga Pass / footprints 3631-3633 of 4770")
	)
	(layers
		(0 "F.Cu" signal "TOP")
		(4 "In1.Cu" signal "L2GND")
		(6 "In2.Cu" signal "L3")
		(8 "In3.Cu" signal "L4GND")
		(10 "In4.Cu" signal "L5")
		(12 "In5.Cu" signal "L6GND")
		(14 "In6.Cu" signal "L7VCC")
		(16 "In7.Cu" signal "L8VCC")
		(18 "In8.Cu" signal "L9GND")
		(20 "In9.Cu" signal "L10")
		(22 "In10.Cu" signal "L11GND")
		(24 "In11.Cu" signal "L12")
		(26 "In12.Cu" signal "L13GND")
		(2 "B.Cu" signal "BOTTOM")
		(9 "F.Adhes" user "F.Adhesive")
		(11 "B.Adhes" user "B.Adhesive")
		(13 "F.Paste" user "Package Geometry/Pastemask Top")
		(15 "B.Paste" user "Package Geometry/Pastemask Bottom")
		(5 "F.SilkS" user "Ref Des/Silkscreen Top")
		(7 "B.SilkS" user "Ref Des/Silkscreen Bottom")
		(1 "F.Mask" user "Board Geometry/Soldermask Top")
		(3 "B.Mask" user "Board Geometry/Soldermask Bottom")
		(17 "Dwgs.User" user "User.Drawings")
		(19 "Cmts.User" user "User.Comments")
		(21 "Eco1.User" user "User.Eco1")
		(23 "Eco2.User" user "User.Eco2")
		(25 "Edge.Cuts" user "Board Geometry/Outline")
		(27 "Margin" user)
		(31 "F.CrtYd" user "Package Geometry/Place Bound Top")
		(29 "B.CrtYd" user "Package Geometry/Place Bound Bottom")
		(35 "F.Fab" user "Ref Des/Assembly Top")
		(33 "B.Fab" user "Ref Des/Assembly Bottom")
	)
	(footprint ""
		(layer "B.Cu")
		(at 365.887 -23.241)
		(property "Reference" "C3T13"
			(at 3.14833 3.937 270)
			(unlocked yes)
			(layer "B.SilkS")
			(effects
				(font
					(size 0.7874 0.5842)
					(thickness 0.1524)
				)
				(justify mirror)
			)
		)
		(property "Value" ""
			(at 0 0 0)
			(layer "B.Fab")
			(effects
				(font
					(size 1.27 1.27)
				)
				(justify mirror)
			)
		)
		(duplicate_pad_numbers_are_jumpers no)
		(fp_line
			(start -2.504948 -1.616456)
			(end -2.504948 1.633728)
			(stroke
				(width 0.1524)
				(type default)
			)
			(layer "B.SilkS")
		)
		(fp_line
			(start -2.504948 1.633728)
			(end -1.6002 1.633728)
			(stroke
				(width 0.1524)
				(type default)
			)
			(layer "B.SilkS")
		)
		(fp_line
			(start -2.286 7.366)
			(end -2.286 1.63195)
			(stroke
				(width 0.1524)
				(type default)
			)
			(layer "B.SilkS")
		)
		(fp_line
			(start -2.286 7.366)
			(end -1.600708 7.366)
			(stroke
				(width 0.1524)
				(type default)
			)
			(layer "B.SilkS")
		)
		(fp_line
			(start -1.6002 -1.616456)
			(end -2.504948 -1.616456)
			(stroke
				(width 0.1524)
				(type default)
			)
			(layer "B.SilkS")
		)
		(fp_line
			(start 1.6002 -1.616456)
			(end 2.563114 -1.616456)
			(stroke
				(width 0.1524)
				(type default)
			)
			(layer "B.SilkS")
		)
		(fp_line
			(start 2.286 7.366)
			(end 1.60147 7.366)
			(stroke
				(width 0.1524)
				(type default)
			)
			(layer "B.SilkS")
		)
		(fp_line
			(start 2.286 7.366)
			(end 2.286 1.632712)
			(stroke
				(width 0.1524)
				(type default)
			)
			(layer "B.SilkS")
		)
		(fp_line
			(start 2.563114 -1.616456)
			(end 2.563114 1.633728)
			(stroke
				(width 0.1524)
				(type default)
			)
			(layer "B.SilkS")
		)
		(fp_line
			(start 2.563114 1.633728)
			(end 1.6002 1.633728)
			(stroke
				(width 0.1524)
				(type default)
			)
			(layer "B.SilkS")
		)
		(fp_rect
			(start 2.286 7.366)
			(end -2.286 -0.254)
			(stroke
				(width 0)
				(type default)
			)
			(fill no)
			(layer "B.CrtYd")
		)
		(fp_line
			(start -2.286 -0.254)
			(end -2.286 7.366)
			(stroke
				(width 0.1)
				(type default)
			)
			(layer "B.Fab")
		)
		(fp_line
			(start -2.286 7.366)
			(end 2.286 7.366)
			(stroke
				(width 0.1)
				(type default)
			)
			(layer "B.Fab")
		)
		(fp_line
			(start 2.286 -0.254)
			(end -2.286 -0.254)
			(stroke
				(width 0.1)
				(type default)
			)
			(layer "B.Fab")
		)
		(fp_line
			(start 2.286 7.366)
			(end 2.286 -0.254)
			(stroke
				(width 0.1)
				(type default)
			)
			(layer "B.Fab")
		)
		(pad "1" smd rect
			(at 0 0 180)
			(size 2.54 3.048)
			(layers "B.Cu" "B.Mask" "B.Paste")
			(net "P12V_STBY")
		)
		(pad "2" smd rect
			(at 0 7.112 180)
			(size 2.54 3.048)
			(layers "B.Cu" "B.Mask" "B.Paste")
			(net "GND")
		)
	)
	(footprint ""
		(layer "B.Cu")
		(at 407.162 -27.94 90)
		(property "Reference" "R25W109"
			(at 0.8382 -0.67818 90)
			(unlocked yes)
			(layer "B.SilkS")
			(effects
				(font
					(size 0.4064 0.254)
					(thickness 0.1524)
				)
				(justify left mirror)
			)
		)
		(property "Value" ""
			(at 0 0 90)
			(layer "B.Fab")
			(effects
				(font
					(size 1.27 1.27)
				)
				(justify mirror)
			)
		)
		(duplicate_pad_numbers_are_jumpers no)
		(fp_poly
			(pts
				(xy 0.2794 -0.1016) (xy -0.2794 -0.1016) (xy -0.2794 0.9906) (xy 0.2794 0.9906)
			)
			(stroke
				(width 0)
				(type default)
			)
			(fill no)
			(layer "B.CrtYd")
		)
		(fp_line
			(start 0.2794 -0.1016)
			(end 0.2794 0.9906)
			(stroke
				(width 0.1)
				(type default)
			)
			(layer "B.Fab")
		)
		(fp_line
			(start -0.2794 -0.1016)
			(end 0.2794 -0.1016)
			(stroke
				(width 0.1)
				(type default)
			)
			(layer "B.Fab")
		)
		(fp_line
			(start 0.2794 0.9906)
			(end -0.2794 0.9906)
			(stroke
				(width 0.1)
				(type default)
			)
			(layer "B.Fab")
		)
		(fp_line
			(start -0.2794 0.9906)
			(end -0.2794 -0.1016)
			(stroke
				(width 0.1)
				(type default)
			)
			(layer "B.Fab")
		)
		(pad "1" smd rect
			(at 0 0 270)
			(size 0.508 0.508)
			(layers "B.Cu" "B.Mask" "B.Paste")
			(net "P3V3_STBY")
		)
		(pad "2" smd rect
			(at 0 0.889 270)
			(size 0.508 0.508)
			(layers "B.Cu" "B.Mask" "B.Paste")
			(net "TP_RGMII2TXD3_GPIOU3")
		)
		(zone
			(layer "B.Cu")
			(hatch none 0.5)
			(connect_pads
				(clearance 0)
			)
			(min_thickness 0.25)
			(keepout
				(tracks allowed)
				(vias not_allowed)
				(pads allowed)
				(copperpour not_allowed)
				(footprints allowed)
			)
			(placement
				(enabled no)
				(sheetname "")
			)
			(fill
				(thermal_gap 0.5)
				(thermal_bridge_width 0.5)
				(island_removal_mode 0)
			)
			(polygon
				(pts
					(xy 407.416 -28.194) (xy 407.416 -27.686) (xy 407.797 -27.686) (xy 407.797 -28.194)
				)
			)
		)
		(zone
			(layer "B.Cu")
			(hatch none 0.5)
			(connect_pads
				(clearance 0)
			)
			(min_thickness 0.25)
			(keepout
				(tracks not_allowed)
				(vias allowed)
				(pads allowed)
				(copperpour not_allowed)
				(footprints allowed)
			)
			(placement
				(enabled no)
				(sheetname "")
			)
			(fill
				(thermal_gap 0.5)
				(thermal_bridge_width 0.5)
				(island_removal_mode 0)
			)
			(polygon
				(pts
					(xy 407.797 -28.194) (xy 407.797 -27.686) (xy 407.416 -27.686) (xy 407.416 -28.194)
				)
			)
		)
	)
	(footprint ""
		(layer "B.Cu")
		(at 392.498834 -107.356148)
		(property "Reference" "R2N4"
			(at 0 0 0)
			(layer "B.SilkS")
			(hide yes)
			(effects
				(font
					(size 1.27 1.27)
				)
				(justify mirror)
			)
		)
		(property "Value" ""
			(at 0 0 0)
			(layer "B.Fab")
			(effects
				(font
					(size 1.27 1.27)
				)
				(justify mirror)
			)
		)
		(duplicate_pad_numbers_are_jumpers no)
		(fp_poly
			(pts
				(xy 0.2794 -0.1016) (xy -0.2794 -0.1016) (xy -0.2794 0.9906) (xy 0.2794 0.9906)
			)
			(stroke
				(width 0)
				(type default)
			)
			(fill no)
			(layer "B.CrtYd")
		)
		(fp_line
			(start -0.2794 -0.1016)
			(end 0.2794 -0.1016)
			(stroke
				(width 0.1)
				(type default)
			)
			(layer "B.Fab")
		)
		(fp_line
			(start -0.2794 0.9906)
			(end -0.2794 -0.1016)
			(stroke
				(width 0.1)
				(type default)
			)
			(layer "B.Fab")
		)
		(fp_line
			(start 0.2794 -0.1016)
			(end 0.2794 0.9906)
			(stroke
				(width 0.1)
				(type default)
			)
			(layer "B.Fab")
		)
		(fp_line
			(start 0.2794 0.9906)
			(end -0.2794 0.9906)
			(stroke
				(width 0.1)
				(type default)
			)
			(layer "B.Fab")
		)
		(pad "1" smd rect
			(at 0 0 180)
			(size 0.508 0.508)
			(layers "B.Cu" "B.Mask" "B.Paste")
			(net "P1V05_PCH_STBY_KR_PLL")
		)
		(pad "2" smd rect
			(at 0 0.889 180)
			(size 0.508 0.508)
			(layers "B.Cu" "B.Mask" "B.Paste")
			(net "A_KR0_RBIAS")
		)
		(zone
			(layer "B.Cu")
			(hatch none 0.5)
			(connect_pads
				(clearance 0)
			)
			(min_thickness 0.25)
			(keepout
				(tracks allowed)
				(vias not_allowed)
				(pads allowed)
				(copperpour not_allowed)
				(footprints allowed)
			)
			(placement
				(enabled no)
				(sheetname "")
			)
			(fill
				(thermal_gap 0.5)
				(thermal_bridge_width 0.5)
				(island_removal_mode 0)
			)
			(polygon
				(pts
					(xy 392.752834 -107.102148) (xy 392.244834 -107.102148) (xy 392.244834 -106.721148) (xy 392.752834 -106.721148)
				)
			)
		)
		(zone
			(layer "B.Cu")
			(hatch none 0.5)
			(connect_pads
				(clearance 0)
			)
			(min_thickness 0.25)
			(keepout
				(tracks not_allowed)
				(vias allowed)
				(pads allowed)
				(copperpour not_allowed)
				(footprints allowed)
			)
			(placement
				(enabled no)
				(sheetname "")
			)
			(fill
				(thermal_gap 0.5)
				(thermal_bridge_width 0.5)
				(island_removal_mode 0)
			)
			(polygon
				(pts
					(xy 392.752834 -106.721148) (xy 392.244834 -106.721148) (xy 392.244834 -107.102148) (xy 392.752834 -107.102148)
				)
			)
		)
	)
)
